#ISCELL
  mstr_misc dns *
  *
#ISCELL
  pure_quanta quanta_title_block_c *
  *
#ISCELL
  pure_quanta_power cad_note *
  *
#CELL
  pure_quanta q_res *
  page443_i10
#CELL
  pure_quanta q_res *
  page443_i11
#CELL
  pure_quanta q_inductor *
  page443_i12
#CELL
  pure_quanta q_cap *
  page443_i13
#CELL
  pure_quanta q_cap *
  page443_i14
#ISCELL
  pure_quanta_power p1v0 *
  page443_i15
#CELL
  pure_quanta q_cap *
  page443_i16
#CELL
  pure_quanta q_cap *
  page443_i17
#CELL
  pure_quanta q_cap *
  page443_i18
#ISCELL
  pure_quanta_power universal_gnd *
  page443_i19
#CELL
  pure_quanta q_cap *
  page443_i20
#ISCELL
  pure_quanta_power universal_gnd *
  page443_i21
#CELL
  pure_quanta q_cap *
  page443_i22
#CELL
  pure_quanta q_cap *
  page443_i23
#CELL
  pure_quanta q_cap *
  page443_i24
#CELL
  pure_quanta q_cap *
  page443_i25
#CELL
  pure_quanta q_cap *
  page443_i26
#CELL
  pure_quanta q_cap *
  page443_i27
#CELL
  pure_quanta q_cap *
  page443_i28
#CELL
  pure_quanta q_cap *
  page443_i29
#ISCELL
  pure_quanta_power p1v0 *
  page443_i3
#CELL
  pure_quanta q_inductor *
  page443_i30
#ISCELL
  pure_quanta_power vcc_core *
  page443_i31
#ISCELL
  pure_quanta_power vcc_core *
  page443_i33
#CELL
  pure_quanta q_cap *
  page443_i34
#ISCELL
  pure_quanta_power universal_gnd *
  page443_i35
#CELL
  pure_quanta q_cap *
  page443_i37
#CELL
  pure_quanta q_cap *
  page443_i38
#CELL
  pure_quanta q_cap *
  page443_i39
#CELL
  pure_quanta q_res *
  page443_i4
#CELL
  pure_quanta q_cap *
  page443_i40
#CELL
  pure_quanta q_cap *
  page443_i41
#CELL
  pure_quanta q_cap *
  page443_i42
#CELL
  pure_quanta q_cap *
  page443_i43
#CELL
  pure_quanta q_cap *
  page443_i44
#CELL
  pure_quanta q_cap *
  page443_i45
#CELL
  pure_quanta q_cap *
  page443_i46
#CELL
  pure_quanta q_cap *
  page443_i47
#CELL
  pure_quanta q_cap *
  page443_i48
#CELL
  pure_quanta q_cap *
  page443_i49
#CELL
  pure_quanta q_res *
  page443_i5
#CELL
  pure_quanta q_cap *
  page443_i50
#CELL
  pure_quanta q_cap *
  page443_i51
#CELL
  pure_quanta q_cap *
  page443_i52
#CELL
  pure_quanta q_cap *
  page443_i53
#CELL
  pure_quanta q_cap *
  page443_i54
#CELL
  pure_quanta q_cap *
  page443_i55
#CELL
  pure_quanta q_cap *
  page443_i57
#CELL
  pure_quanta q_cap *
  page443_i58
#CELL
  pure_quanta q_cap *
  page443_i59
#ISCELL
  pure_quanta_power p1v0 *
  page443_i6
#CELL
  pure_quanta q_cap *
  page443_i60
#ISCELL
  pure_quanta_power universal_gnd *
  page443_i61
#CELL
  pure_quanta q_cap *
  page443_i62
#ISCELL
  pure_quanta_power universal_gnd *
  page443_i63
#CELL
  pure_quanta q_cap *
  page443_i65
#CELL
  pure_quanta q_cap *
  page443_i66
#CELL
  pure_quanta q_cap *
  page443_i67
#ISCELL
  pure_quanta_power vcc_core *
  page443_i68
#CELL
  pure_quanta q_cap *
  page443_i69
#ISCELL
  pure_quanta_power universal_gnd *
  page443_i7
#CELL
  pure_quanta q_cap *
  page443_i70
#CELL
  pure_quanta q_cap *
  page443_i71
#CELL
  pure_quanta q_cap *
  page443_i72
#CELL
  pure_quanta q_cap *
  page443_i73
#CELL
  pure_quanta q_cap *
  page443_i74
#CELL
  pure_quanta q_cap *
  page443_i75
#CELL
  pure_quanta q_cap *
  page443_i76
#CELL
  pure_quanta q_cap *
  page443_i77
#CELL
  pure_quanta q_cap *
  page443_i78
#CELL
  pure_quanta q_cap *
  page443_i79
#CELL
  pure_quanta q_cap *
  page443_i8
#CELL
  pure_quanta q_cap *
  page443_i80
#CELL
  pure_quanta q_cap *
  page443_i81
#CELL
  pure_quanta q_cap *
  page443_i82
#ISCELL
  pure_quanta_power universal_gnd *
  page443_i83
#CELL
  pure_quanta q_cap *
  page443_i84
#CELL
  pure_quanta q_cap *
  page443_i85
#CELL
  pure_quanta q_cap *
  page443_i86
#CELL
  pure_quanta q_cap *
  page443_i87
#CELL
  pure_quanta q_inductor *
  page443_i88
#CELL
  pure_quanta q_res *
  page443_i89
#CELL
  pure_quanta q_cap *
  page443_i9
#CELL
  pure_quanta q_cap *
  page443_i90
#CELL
  pure_quanta q_cap *
  page443_i91
#CELL
  pure_quanta q_cap *
  page443_i92
#CELL
  pure_quanta q_cap *
  page443_i93
#CELL
  pure_quanta q_capp *
  page443_i94
#CELL
  pure_quanta q_capp *
  page443_i95
#CELL
  pure_quanta q_cap *
  page443_i96
